# BASEBOARD_FAB2 (Tioga Pass) — schematic netlist excerpt (pin names and nets, part order shuffled) for the footprints in the layout excerpt that follows; sources: Cadence DE-HDL packaged netlist, KiCad conversion of Wiwynn_Tioga_Pass_MB.brd

C2M14  CAP  0.22UF 16V 10% X7R  pkg 0402  page 106 : A = P3E_CPU0_PE3_OCP_TXP<8> ; B = P3E_OCP_CPU0_PE3_C_TXP<8>
C3P40  CAP  0.22UF 16V 10% X7R  pkg 0402  page 107 : A = P3E_CPU0_PE1_SS_TXN<7> ; B = P3E_CPU0_PE1_PCH_TXN<7>
C4L2  CAP  10UF 4V 20% X6S  pkg 0603LF  page 232 : A = PVPP_DEF ; B = GND

(kicad_pcb
	(version 20260206)
	(generator "pcbnew")
	(generator_version "10.0")
	(general
		(thickness 1.6)
		(legacy_teardrops no)
	)
	(paper "A4")
	(title_block
		(title "Wiwynn_Tioga_Pass_MB.brd")
		(comment 1 "Tioga Pass / footprints 3334-3336 of 4770")
	)
	(layers
		(0 "F.Cu" signal "TOP")
		(4 "In1.Cu" signal "L2GND")
		(6 "In2.Cu" signal "L3")
		(8 "In3.Cu" signal "L4GND")
		(10 "In4.Cu" signal "L5")
		(12 "In5.Cu" signal "L6GND")
		(14 "In6.Cu" signal "L7VCC")
		(16 "In7.Cu" signal "L8VCC")
		(18 "In8.Cu" signal "L9GND")
		(20 "In9.Cu" signal "L10")
		(22 "In10.Cu" signal "L11GND")
		(24 "In11.Cu" signal "L12")
		(26 "In12.Cu" signal "L13GND")
		(2 "B.Cu" signal "BOTTOM")
		(9 "F.Adhes" user "F.Adhesive")
		(11 "B.Adhes" user "B.Adhesive")
		(13 "F.Paste" user "Package Geometry/Pastemask Top")
		(15 "B.Paste" user "Package Geometry/Pastemask Bottom")
		(5 "F.SilkS" user "Ref Des/Silkscreen Top")
		(7 "B.SilkS" user "Ref Des/Silkscreen Bottom")
		(1 "F.Mask" user "Board Geometry/Soldermask Top")
		(3 "B.Mask" user "Board Geometry/Soldermask Bottom")
		(17 "Dwgs.User" user "User.Drawings")
		(19 "Cmts.User" user "User.Comments")
		(21 "Eco1.User" user "User.Eco1")
		(23 "Eco2.User" user "User.Eco2")
		(25 "Edge.Cuts" user "Board Geometry/Outline")
		(27 "Margin" user)
		(31 "F.CrtYd" user "Package Geometry/Place Bound Top")
		(29 "B.CrtYd" user "Package Geometry/Place Bound Bottom")
		(35 "F.Fab" user "Ref Des/Assembly Top")
		(33 "B.Fab" user "Ref Des/Assembly Bottom")
	)
	(footprint ""
		(layer "B.Cu")
		(at 443.865 -116.49202)
		(property "Reference" "C2M14"
			(at 0 0 0)
			(layer "B.SilkS")
			(hide yes)
			(effects
				(font
					(size 1.27 1.27)
				)
				(justify mirror)
			)
		)
		(property "Value" ""
			(at 0 0 0)
			(layer "B.Fab")
			(effects
				(font
					(size 1.27 1.27)
				)
				(justify mirror)
			)
		)
		(duplicate_pad_numbers_are_jumpers no)
		(fp_rect
			(start -0.3048 0.9906)
			(end 0.3048 -0.1016)
			(stroke
				(width 0)
				(type default)
			)
			(fill no)
			(layer "B.CrtYd")
		)
		(fp_line
			(start -0.3048 -0.1016)
			(end 0.3048 -0.1016)
			(stroke
				(width 0.1)
				(type default)
			)
			(layer "B.Fab")
		)
		(fp_line
			(start -0.3048 0.9906)
			(end -0.3048 -0.1016)
			(stroke
				(width 0.1)
				(type default)
			)
			(layer "B.Fab")
		)
		(fp_line
			(start 0.3048 -0.1016)
			(end 0.3048 0.9906)
			(stroke
				(width 0.1)
				(type default)
			)
			(layer "B.Fab")
		)
		(fp_line
			(start 0.3048 0.9906)
			(end -0.3048 0.9906)
			(stroke
				(width 0.1)
				(type default)
			)
			(layer "B.Fab")
		)
		(pad "1" smd rect
			(at 0 0 180)
			(size 0.508 0.508)
			(layers "B.Cu" "B.Mask" "B.Paste")
			(net "P3E_CPU0_PE3_OCP_TXP<8>")
		)
		(pad "2" smd rect
			(at 0 0.889 180)
			(size 0.508 0.508)
			(layers "B.Cu" "B.Mask" "B.Paste")
			(net "P3E_OCP_CPU0_PE3_C_TXP<8>")
		)
		(zone
			(layer "B.Cu")
			(hatch none 0.5)
			(connect_pads
				(clearance 0)
			)
			(min_thickness 0.25)
			(keepout
				(tracks not_allowed)
				(vias allowed)
				(pads allowed)
				(copperpour not_allowed)
				(footprints allowed)
			)
			(placement
				(enabled no)
				(sheetname "")
			)
			(fill
				(thermal_gap 0.5)
				(thermal_bridge_width 0.5)
				(island_removal_mode 0)
			)
			(polygon
				(pts
					(xy 443.611 -115.85702) (xy 444.119 -115.85702) (xy 444.119 -116.23802) (xy 443.611 -116.23802)
				)
			)
		)
		(zone
			(layer "B.Cu")
			(hatch none 0.5)
			(connect_pads
				(clearance 0)
			)
			(min_thickness 0.25)
			(keepout
				(tracks allowed)
				(vias not_allowed)
				(pads allowed)
				(copperpour not_allowed)
				(footprints allowed)
			)
			(placement
				(enabled no)
				(sheetname "")
			)
			(fill
				(thermal_gap 0.5)
				(thermal_bridge_width 0.5)
				(island_removal_mode 0)
			)
			(polygon
				(pts
					(xy 443.611 -115.85702) (xy 444.119 -115.85702) (xy 444.119 -116.23802) (xy 443.611 -116.23802)
				)
			)
		)
	)
	(footprint ""
		(layer "B.Cu")
		(at 318.483996 -154.801824 -90)
		(property "Reference" "C4L2"
			(at 0 0 90)
			(layer "B.SilkS")
			(hide yes)
			(effects
				(font
					(size 1.27 1.27)
				)
				(justify mirror)
			)
		)
		(property "Value" ""
			(at 0 0 90)
			(layer "B.Fab")
			(effects
				(font
					(size 1.27 1.27)
				)
				(justify mirror)
			)
		)
		(duplicate_pad_numbers_are_jumpers no)
		(fp_poly
			(pts
				(xy 0.4953 -0.2032) (xy -0.4953 -0.2032) (xy -0.4953 1.6002) (xy 0.4953 1.6002)
			)
			(stroke
				(width 0)
				(type default)
			)
			(fill no)
			(layer "B.CrtYd")
		)
		(fp_line
			(start -0.4953 1.6002)
			(end 0.4953 1.6002)
			(stroke
				(width 0.1)
				(type default)
			)
			(layer "B.Fab")
		)
		(fp_line
			(start 0.4953 1.6002)
			(end 0.4953 -0.2032)
			(stroke
				(width 0.1)
				(type default)
			)
			(layer "B.Fab")
		)
		(fp_line
			(start -0.4953 -0.2032)
			(end -0.4953 1.6002)
			(stroke
				(width 0.1)
				(type default)
			)
			(layer "B.Fab")
		)
		(fp_line
			(start 0.4953 -0.2032)
			(end -0.4953 -0.2032)
			(stroke
				(width 0.1)
				(type default)
			)
			(layer "B.Fab")
		)
		(pad "1" smd rect
			(at 0 0 90)
			(size 0.762 0.889)
			(layers "B.Cu" "B.Mask" "B.Paste")
			(net "PVPP_DEF")
		)
		(pad "2" smd rect
			(at 0 1.397 90)
			(size 0.762 0.889)
			(layers "B.Cu" "B.Mask" "B.Paste")
			(net "GND")
		)
		(zone
			(layer "B.Cu")
			(hatch none 0.5)
			(connect_pads
				(clearance 0)
			)
			(min_thickness 0.25)
			(keepout
				(tracks not_allowed)
				(vias allowed)
				(pads allowed)
				(copperpour not_allowed)
				(footprints allowed)
			)
			(placement
				(enabled no)
				(sheetname "")
			)
			(fill
				(thermal_gap 0.5)
				(thermal_bridge_width 0.5)
				(island_removal_mode 0)
			)
			(polygon
				(pts
					(xy 318.039496 -154.420824) (xy 318.039496 -155.182824) (xy 317.531496 -155.182824) (xy 317.531496 -154.420824)
				)
			)
		)
	)
	(footprint ""
		(layer "B.Cu")
		(at 358.44988 -77.923136 180)
		(property "Reference" "C3P40"
			(at 0 0 0)
			(layer "B.SilkS")
			(hide yes)
			(effects
				(font
					(size 1.27 1.27)
				)
				(justify mirror)
			)
		)
		(property "Value" ""
			(at 0 0 0)
			(layer "B.Fab")
			(effects
				(font
					(size 1.27 1.27)
				)
				(justify mirror)
			)
		)
		(duplicate_pad_numbers_are_jumpers no)
		(fp_poly
			(pts
				(xy -0.3048 -0.1016) (xy -0.3048 0.9906) (xy 0.3048 0.9906) (xy 0.3048 -0.1016)
			)
			(stroke
				(width 0)
				(type default)
			)
			(fill no)
			(layer "B.CrtYd")
		)
		(fp_line
			(start 0.3048 0.9906)
			(end -0.3048 0.9906)
			(stroke
				(width 0.1)
				(type default)
			)
			(layer "B.Fab")
		)
		(fp_line
			(start 0.3048 -0.1016)
			(end 0.3048 0.9906)
			(stroke
				(width 0.1)
				(type default)
			)
			(layer "B.Fab")
		)
		(fp_line
			(start -0.3048 0.9906)
			(end -0.3048 -0.1016)
			(stroke
				(width 0.1)
				(type default)
			)
			(layer "B.Fab")
		)
		(fp_line
			(start -0.3048 -0.1016)
			(end 0.3048 -0.1016)
			(stroke
				(width 0.1)
				(type default)
			)
			(layer "B.Fab")
		)
		(pad "1" smd rect
			(at 0 0)
			(size 0.508 0.508)
			(layers "B.Cu" "B.Mask" "B.Paste")
			(net "P3E_CPU0_PE1_SS_TXN<7>")
		)
		(pad "2" smd rect
			(at 0 0.889)
			(size 0.508 0.508)
			(layers "B.Cu" "B.Mask" "B.Paste")
			(net "P3E_CPU0_PE1_PCH_TXN<7>")
		)
		(zone
			(layer "B.Cu")
			(hatch none 0.5)
			(connect_pads
				(clearance 0)
			)
			(min_thickness 0.25)
			(keepout
				(tracks not_allowed)
				(vias allowed)
				(pads allowed)
				(copperpour not_allowed)
				(footprints allowed)
			)
			(placement
				(enabled no)
				(sheetname "")
			)
			(fill
				(thermal_gap 0.5)
				(thermal_bridge_width 0.5)
				(island_removal_mode 0)
			)
			(polygon
				(pts
					(xy 358.19588 -78.558136) (xy 358.70388 -78.558136) (xy 358.70388 -78.177136) (xy 358.19588 -78.177136)
				)
			)
		)
		(zone
			(layer "B.Cu")
			(hatch none 0.5)
			(connect_pads
				(clearance 0)
			)
			(min_thickness 0.25)
			(keepout
				(tracks allowed)
				(vias not_allowed)
				(pads allowed)
				(copperpour not_allowed)
				(footprints allowed)
			)
			(placement
				(enabled no)
				(sheetname "")
			)
			(fill
				(thermal_gap 0.5)
				(thermal_bridge_width 0.5)
				(island_removal_mode 0)
			)
			(polygon
				(pts
					(xy 358.19588 -78.177136) (xy 358.70388 -78.177136) (xy 358.70388 -78.558136) (xy 358.19588 -78.558136)
				)
			)
		)
	)
)
